# T6G (Grand Teton) — schematic netlist excerpt (pin names and nets, part order shuffled) for the footprints in the layout excerpt that follows; sources: Cadence DE-HDL packaged netlist, KiCad conversion of 04192023_DAF0TMB3IC0_F0TG_MB_C_brd_V02_OCP.brd

R45  Q_RES  10K 1% CHIP  pkg 0402LF  page 133 : A = P3V3_OCP_SFF ; B = PU_OCP_SFF_WAKE_OE
R1702  Q_RES  4.7K 5% CHIP  pkg 0402LF  page 148 : A = P1V8_AUX ; B = SMB_M2_P1_1V8AUX_SDA_R

(kicad_pcb
	(version 20260206)
	(generator "pcbnew")
	(generator_version "10.0")
	(general
		(thickness 1.6)
		(legacy_teardrops no)
	)
	(paper "A4")
	(title_block
		(title "04192023_DAF0TMB3IC0_F0TG_MB_C_brd_V02_OCP.brd")
		(comment 1 "Grand Teton / footprints 1834-1835 of 8354")
	)
	(layers
		(0 "F.Cu" signal "TOP")
		(4 "In1.Cu" signal "GND")
		(6 "In2.Cu" signal "IN1")
		(8 "In3.Cu" signal "GND1")
		(10 "In4.Cu" signal "IN2")
		(12 "In5.Cu" signal "GND2")
		(14 "In6.Cu" signal "IN3")
		(16 "In7.Cu" signal "GND3")
		(18 "In8.Cu" signal "VCC")
		(20 "In9.Cu" signal "VCC1")
		(22 "In10.Cu" signal "GND4")
		(24 "In11.Cu" signal "IN4")
		(26 "In12.Cu" signal "GND5")
		(28 "In13.Cu" signal "IN5")
		(30 "In14.Cu" signal "GND6")
		(32 "In15.Cu" signal "IN6")
		(34 "In16.Cu" signal "GND7")
		(2 "B.Cu" signal "BOTTOM")
		(9 "F.Adhes" user "F.Adhesive")
		(11 "B.Adhes" user "B.Adhesive")
		(13 "F.Paste" user "Package Geometry/Pastemask Top")
		(15 "B.Paste" user "Package Geometry/Pastemask Bottom")
		(5 "F.SilkS" user "Ref Des/Silkscreen Top")
		(7 "B.SilkS" user "Ref Des/Silkscreen Bottom")
		(1 "F.Mask" user "Board Geometry/Soldermask Top")
		(3 "B.Mask" user "Board Geometry/Soldermask Bottom")
		(17 "Dwgs.User" user "User.Drawings")
		(19 "Cmts.User" user "User.Comments")
		(21 "Eco1.User" user "User.Eco1")
		(23 "Eco2.User" user "User.Eco2")
		(25 "Edge.Cuts" user "Board Geometry/Outline")
		(27 "Margin" user)
		(31 "F.CrtYd" user "Package Geometry/Place Bound Top")
		(29 "B.CrtYd" user "Package Geometry/Place Bound Bottom")
		(35 "F.Fab" user "Ref Des/Assembly Top")
		(33 "B.Fab" user "Ref Des/Assembly Bottom")
	)
	(footprint ""
		(layer "F.Cu")
		(at 455.01306 -38.565836)
		(property "Reference" "R45"
			(at 0 0 0)
			(layer "F.SilkS")
			(hide yes)
			(effects
				(font
					(size 1.27 1.27)
				)
			)
		)
		(property "Value" ""
			(at 0 0 0)
			(layer "F.Fab")
			(effects
				(font
					(size 1.27 1.27)
				)
			)
		)
		(duplicate_pad_numbers_are_jumpers no)
		(fp_line
			(start -0.7874 -0.4064)
			(end 0.7874 -0.4064)
			(stroke
				(width 0.1524)
				(type default)
			)
			(layer "F.SilkS")
		)
		(fp_line
			(start -0.7874 0.4064)
			(end -0.7874 -0.4064)
			(stroke
				(width 0.1524)
				(type default)
			)
			(layer "F.SilkS")
		)
		(fp_line
			(start 0.7874 -0.4064)
			(end 0.7874 0.4064)
			(stroke
				(width 0.1524)
				(type default)
			)
			(layer "F.SilkS")
		)
		(fp_line
			(start 0.7874 0.4064)
			(end -0.7874 0.4064)
			(stroke
				(width 0.1524)
				(type default)
			)
			(layer "F.SilkS")
		)
		(fp_line
			(start -0.67945 -0.305054)
			(end -0.12065 -0.305054)
			(stroke
				(width 0.1)
				(type default)
			)
			(layer "F.Fab")
		)
		(fp_line
			(start -0.67945 0.3048)
			(end -0.67945 -0.305054)
			(stroke
				(width 0.1)
				(type default)
			)
			(layer "F.Fab")
		)
		(fp_line
			(start -0.12065 -0.305054)
			(end -0.12065 -0.2794)
			(stroke
				(width 0.1)
				(type default)
			)
			(layer "F.Fab")
		)
		(fp_line
			(start -0.12065 -0.2794)
			(end 0.12065 -0.2794)
			(stroke
				(width 0.1)
				(type default)
			)
			(layer "F.Fab")
		)
		(fp_line
			(start -0.12065 0.2794)
			(end -0.12065 0.3048)
			(stroke
				(width 0.1)
				(type default)
			)
			(layer "F.Fab")
		)
		(fp_line
			(start -0.12065 0.3048)
			(end -0.67945 0.3048)
			(stroke
				(width 0.1)
				(type default)
			)
			(layer "F.Fab")
		)
		(fp_line
			(start 0.120396 0.2794)
			(end -0.12065 0.2794)
			(stroke
				(width 0.1)
				(type default)
			)
			(layer "F.Fab")
		)
		(fp_line
			(start 0.120396 0.3048)
			(end 0.120396 0.2794)
			(stroke
				(width 0.1)
				(type default)
			)
			(layer "F.Fab")
		)
		(fp_line
			(start 0.12065 -0.3048)
			(end 0.67945 -0.3048)
			(stroke
				(width 0.1)
				(type default)
			)
			(layer "F.Fab")
		)
		(fp_line
			(start 0.12065 -0.2794)
			(end 0.12065 -0.3048)
			(stroke
				(width 0.1)
				(type default)
			)
			(layer "F.Fab")
		)
		(fp_line
			(start 0.67945 -0.3048)
			(end 0.67945 0.3048)
			(stroke
				(width 0.1)
				(type default)
			)
			(layer "F.Fab")
		)
		(fp_line
			(start 0.67945 0.3048)
			(end 0.120396 0.3048)
			(stroke
				(width 0.1)
				(type default)
			)
			(layer "F.Fab")
		)
		(pad "1" smd circle
			(at -0.40005 0)
			(size 0 0)
			(layers "F.Cu" "F.Mask" "F.Paste")
			(net "P3V3_OCP_SFF")
		)
		(pad "2" smd circle
			(at 0.40005 0)
			(size 0 0)
			(layers "F.Cu" "F.Mask" "F.Paste")
			(net "PU_OCP_SFF_WAKE_OE")
		)
	)
	(footprint ""
		(layer "F.Cu")
		(at 148.641562 -41.746424)
		(property "Reference" "R1702"
			(at 0 0 0)
			(layer "F.SilkS")
			(hide yes)
			(effects
				(font
					(size 1.27 1.27)
				)
			)
		)
		(property "Value" ""
			(at 0 0 0)
			(layer "F.Fab")
			(effects
				(font
					(size 1.27 1.27)
				)
			)
		)
		(duplicate_pad_numbers_are_jumpers no)
		(fp_line
			(start -0.7874 -0.4064)
			(end 0.7874 -0.4064)
			(stroke
				(width 0.1524)
				(type default)
			)
			(layer "F.SilkS")
		)
		(fp_line
			(start -0.7874 0.4064)
			(end -0.7874 -0.4064)
			(stroke
				(width 0.1524)
				(type default)
			)
			(layer "F.SilkS")
		)
		(fp_line
			(start 0.7874 -0.4064)
			(end 0.7874 0.4064)
			(stroke
				(width 0.1524)
				(type default)
			)
			(layer "F.SilkS")
		)
		(fp_line
			(start 0.7874 0.4064)
			(end -0.7874 0.4064)
			(stroke
				(width 0.1524)
				(type default)
			)
			(layer "F.SilkS")
		)
		(fp_line
			(start -0.67945 -0.305054)
			(end -0.12065 -0.305054)
			(stroke
				(width 0.1)
				(type default)
			)
			(layer "F.Fab")
		)
		(fp_line
			(start -0.67945 0.3048)
			(end -0.67945 -0.305054)
			(stroke
				(width 0.1)
				(type default)
			)
			(layer "F.Fab")
		)
		(fp_line
			(start -0.12065 -0.305054)
			(end -0.12065 -0.2794)
			(stroke
				(width 0.1)
				(type default)
			)
			(layer "F.Fab")
		)
		(fp_line
			(start -0.12065 -0.2794)
			(end 0.12065 -0.2794)
			(stroke
				(width 0.1)
				(type default)
			)
			(layer "F.Fab")
		)
		(fp_line
			(start -0.12065 0.2794)
			(end -0.12065 0.3048)
			(stroke
				(width 0.1)
				(type default)
			)
			(layer "F.Fab")
		)
		(fp_line
			(start -0.12065 0.3048)
			(end -0.67945 0.3048)
			(stroke
				(width 0.1)
				(type default)
			)
			(layer "F.Fab")
		)
		(fp_line
			(start 0.120396 0.2794)
			(end -0.12065 0.2794)
			(stroke
				(width 0.1)
				(type default)
			)
			(layer "F.Fab")
		)
		(fp_line
			(start 0.120396 0.3048)
			(end 0.120396 0.2794)
			(stroke
				(width 0.1)
				(type default)
			)
			(layer "F.Fab")
		)
		(fp_line
			(start 0.12065 -0.3048)
			(end 0.67945 -0.3048)
			(stroke
				(width 0.1)
				(type default)
			)
			(layer "F.Fab")
		)
		(fp_line
			(start 0.12065 -0.2794)
			(end 0.12065 -0.3048)
			(stroke
				(width 0.1)
				(type default)
			)
			(layer "F.Fab")
		)
		(fp_line
			(start 0.67945 -0.3048)
			(end 0.67945 0.3048)
			(stroke
				(width 0.1)
				(type default)
			)
			(layer "F.Fab")
		)
		(fp_line
			(start 0.67945 0.3048)
			(end 0.120396 0.3048)
			(stroke
				(width 0.1)
				(type default)
			)
			(layer "F.Fab")
		)
		(pad "1" smd circle
			(at -0.40005 0)
			(size 0 0)
			(layers "F.Cu" "F.Mask" "F.Paste")
			(net "P1V8_AUX")
		)
		(pad "2" smd circle
			(at 0.40005 0)
			(size 0 0)
			(layers "F.Cu" "F.Mask" "F.Paste")
			(net "SMB_M2_P1_1V8AUX_SDA_R")
		)
	)
)
